#ISCELL
  logical_power design_note *
  *
#ISCELL
  mstr_misc dns *
  *
#ISCELL
  pure_quanta quanta_title_block_c *
  *
#CELL
  pure_quanta q_res *
  page201_i102
#CELL
  pure_quanta q_cap *
  page201_i103
#CELL
  pure_quanta q_cap *
  page201_i104
#CELL
  pure_quanta q_cap *
  page201_i105
#CELL
  pure_quanta q_cap *
  page201_i106
#ISCELL
  logical_power universal_gnd *
  page201_i107
#ISCELL
  logical_power universal_power *
  page201_i108
#ISCELL
  logical_power universal_power *
  page201_i109
#ISCELL
  logical_power universal_power *
  page201_i110
#ISCELL
  logical_power universal_power *
  page201_i111
#ISCELL
  logical_power universal_gnd *
  page201_i113
#ISCELL
  logical_power universal_gnd *
  page201_i115
#ISCELL
  logical_power universal_gnd *
  page201_i116
#ISCELL
  logical_power universal_gnd *
  page201_i117
#ISCELL
  standard offpage *
  page201_i125
#ISCELL
  standard offpage *
  page201_i126
#CELL
  pure_quanta q_res *
  page201_i127
#CELL
  pure_quanta q_res *
  page201_i128
#ISCELL
  standard offpage *
  page201_i129
#ISCELL
  logical_power universal_power *
  page201_i130
#ISCELL
  logical_power universal_gnd *
  page201_i133
#CELL
  pure_quanta q_res *
  page201_i134
#CELL
  pure_quanta q_res *
  page201_i135
#ISCELL
  standard offpage *
  page201_i139
#ISCELL
  standard offpage *
  page201_i140
#ISCELL
  logical_power universal_power *
  page201_i141
#CELL
  pure_quanta q_res *
  page201_i142
#CELL
  pure_quanta q_res *
  page201_i146
#CELL
  pure_quanta q_res *
  page201_i147
#ISCELL
  standard offpage *
  page201_i150
#ISCELL
  standard offpage *
  page201_i151
#ISCELL
  standard offpage *
  page201_i152
#ISCELL
  standard offpage *
  page201_i153
#ISCELL
  standard offpage *
  page201_i154
#CELL
  pure_quanta q_inductor *
  page201_i155
#ISCELL
  logical_power universal_power *
  page201_i156
#CELL
  pure_quanta q_res *
  page201_i157
#CELL
  pure_quanta 74lvc1g32gw *
  page201_i158
#CELL
  pure_quanta q_xtal_4p_13bi_24gnd *
  page201_i159
#CELL
  pure_quanta q_cap *
  page201_i16
#CELL
  pure_quanta q_res *
  page201_i160
#CELL
  pure_quanta q_res *
  page201_i161
#ISCELL
  logical_power universal_gnd *
  page201_i162
#CELL
  pure_quanta q_res *
  page201_i163
#ISCELL
  logical_power universal_power *
  page201_i164
#CELL
  pure_quanta q_cap *
  page201_i165
#CELL
  pure_quanta q_cap *
  page201_i166
#CELL
  pure_quanta 9fgl0251dkilft *
  page201_i167
#CELL
  pure_quanta q_cap *
  page201_i18
#CELL
  pure_quanta q_cap *
  page201_i19
#ISCELL
  logical_power universal_power *
  page201_i20
#ISCELL
  logical_power universal_gnd *
  page201_i21
#ISCELL
  logical_power universal_gnd *
  page201_i22
#ISCELL
  standard offpage *
  page201_i32
#ISCELL
  logical_power universal_power *
  page201_i33
#ISCELL
  logical_power universal_gnd *
  page201_i35
#CELL
  pure_quanta q_res *
  page201_i69
#ISCELL
  standard offpage *
  page201_i70
#ISCELL
  standard offpage *
  page201_i71
#ISCELL
  standard offpage *
  page201_i72
#ISCELL
  standard offpage *
  page201_i73
#CELL
  pure_quanta q_res *
  page201_i74
#CELL
  pure_quanta q_res *
  page201_i75
#CELL
  pure_quanta q_res *
  page201_i76
#ISCELL
  logical_power universal_power *
  page201_i79
#CELL
  pure_quanta q_cap *
  page201_i80
#ISCELL
  logical_power universal_gnd *
  page201_i81
#ISCELL
  logical_power universal_gnd *
  page201_i82
#CELL
  pure_quanta q_res *
  page201_i84
#CELL
  pure_quanta q_res *
  page201_i85
#ISCELL
  standard offpage *
  page201_i87
#ISCELL
  standard offpage *
  page201_i88
